FILE_TYPE = CONNECTIVITY;
{Allegro Design Entry HDL 17.2-2016 S066 (3851973) 4/6/2020}
"PAGE_NUMBER" = 11;
0"NC";
1"XP5R0V_VCC_ANT\g";
2"SG\g";
3"GPS_UART_RXD";
4"GPS_UART_TXD";
5"GPSTP1_OUT";
6"GPS_RST_N";
7"FPGA_OUT_GPS_RST_N";
8"FPGA_IN_GPSTP1_OUT";
9"GPSTP2_OUT";
10"DBG_UART_GPS_RXD";
11"DBG_UART_GPS_TXD";
12"FPGA_IN_GPSTP2_OUT";
13"UART_GPS_RX_FPGA_TX";
14"XP3R3V_FPGA\g";
15"UART_GPS_TX_FPGA_RX";
16"XP5R0V\g";
17"SG\g";
18"XP3R3V_GPS\g";
19"SG\g";
20"XP3R3V_FPGA\g";
%"RESISTOR"
"1","(-6300,6150)","0","passive","I11";
;
$LOCATION"R109"
CDS_LOCATION"R109"
$SEC"1"
CDS_SEC"1"
PACKAGE"0402"
VALUE"33OHM"
TOLERANCE"1%"
CLS_PN"G155-133R0-01"
SIGNAL_MODEL"DEFAULT_RESISTOR_33OHM_2_1"
CDS_LMAN_SYM_OUTLINE"-50,50,100,-50"
CDS_LIB"passive";
"1"
$PN"1"15;
"2"
$PN"2"4;
%"CAPACITOR"
"1","(-6050,6950)","5","passive","I12";
;
$LOCATION"C72"
CDS_LOCATION"C72"
$SEC"1"
CDS_SEC"1"
VALUE"10UF"
PACKAGE"0805"
VOLTAGE"25V"
CDS_LIB"passive"
CDS_LMAN_SYM_OUTLINE"0,50,50,-50"
CLS_PN"G107-0F106-EM"
TOLERANCE"20%";
"2"
$PN"2"17;
"1"
$PN"1"1;
%"CAPACITOR"
"1","(-5650,6950)","3","passive","I13";
;
$LOCATION"C73"
CDS_LOCATION"C73"
$SEC"1"
CDS_SEC"1"
VOLTAGE"25V"
PACKAGE"0402"
VALUE"0.1UF"
CDS_LMAN_SYM_OUTLINE"0,50,50,-50"
CDS_LIB"passive"
TOLERANCE"10%"
CLS_PN"G105-0B104-EK";
"2"
$PN"2"17;
"1"
$PN"1"1;
%"GND_SG"
"1","(-5250,6600)","0","cls","I14";
;
HDL_POWER"SG"
BODY_TYPE"PLUMBING"
CDS_LIB"cls"
CDS_LMAN_SYM_OUTLINE"0,0,100,-50"
VOLTAGE"0";
"SGND"17;
%"CAPACITOR"
"1","(-5200,6950)","3","passive","I15";
;
$LOCATION"C78"
CDS_LOCATION"C78"
$SEC"1"
CDS_SEC"1"
VOLTAGE"25V"
PACKAGE"0402"
VALUE"0.1UF"
CLS_PN"G105-0B104-EK"
TOLERANCE"10%"
CDS_LIB"passive"
CDS_LMAN_SYM_OUTLINE"0,50,50,-50";
"2"
$PN"2"17;
"1"
$PN"1"1;
%"VCC"
"1","(-4800,7400)","0","cls","I16";
;
HDL_POWER"XP5R0V_VCC_ANT"
VOLTAGE"5"
BODY_TYPE"PLUMBING"
CDS_LIB"cls"
CDS_LMAN_SYM_OUTLINE"-250,250,250,-250";
"$PIN0"1;
%"GND_SG"
"1","(-3850,5400)","0","cls","I17";
;
HDL_POWER"SG"
BODY_TYPE"PLUMBING"
VOLTAGE"0"
CDS_LMAN_SYM_OUTLINE"0,0,100,-50"
CDS_LIB"cls";
"SGND"2;
%"RESISTOR"
"2","(-3450,5800)","0","passive","I18";
;
$LOCATION"R114"
CDS_LOCATION"R114"
$SEC"1"
CDS_SEC"1"
VALUE"4.7KOHM"
PACKAGE"0402"
NO_ASSY"TRUE"
TOLERANCE"1%"
CDS_LIB"passive"
CDS_LMAN_SYM_OUTLINE"-50,50,50,-100"
CLS_PN"G155-14701-01";
"1"
$PN"1"6;
"2"
$PN"2"2;
%"RESISTOR"
"1","(-2050,6050)","0","passive","I20";
;
$LOCATION"R117"
CDS_LOCATION"R117"
$SEC"1"
CDS_SEC"1"
VALUE"33OHM"
PACKAGE"0402"
TOLERANCE"1%"
CLS_PN"G155-133R0-01"
CDS_LIB"passive"
CDS_LMAN_SYM_OUTLINE"-50,50,100,-50"
SIGNAL_MODEL"DEFAULT_RESISTOR_33OHM_2_1";
"1"
$PN"1"5;
"2"
$PN"2"8;
%"RESISTOR"
"2","(-3400,6750)","0","passive","I21";
;
$LOCATION"R115"
CDS_LOCATION"R115"
$SEC"1"
CDS_SEC"1"
VALUE"4.7KOHM"
PACKAGE"0402"
TOLERANCE"1%"
CDS_LIB"passive"
CDS_LMAN_SYM_OUTLINE"-50,50,50,-100"
CLS_PN"G155-14701-01";
"1"
$PN"1"18;
"2"
$PN"2"6;
%"GND_SG"
"1","(-2650,6450)","0","cls","I22";
;
HDL_POWER"SG"
VOLTAGE"0"
CDS_LIB"cls"
CDS_LMAN_SYM_OUTLINE"0,0,100,-50"
BODY_TYPE"PLUMBING";
"SGND"19;
%"CAPACITOR"
"1","(-1600,6850)","5","passive","I24";
;
$LOCATION"C79"
CDS_LOCATION"C79"
$SEC"1"
CDS_SEC"1"
PACKAGE"0805"
VOLTAGE"25V"
VALUE"10UF"
TOLERANCE"20%"
CDS_LIB"passive"
CDS_LMAN_SYM_OUTLINE"0,50,50,-50"
CLS_PN"G107-0F106-EM";
"2"
$PN"2"19;
"1"
$PN"1"18;
%"RESISTOR"
"1","(-2050,6150)","0","passive","I25";
;
$LOCATION"R116"
CDS_LOCATION"R116"
$SEC"1"
CDS_SEC"1"
PACKAGE"0402"
VALUE"33OHM"
TOLERANCE"1%"
CLS_PN"G155-133R0-01"
SIGNAL_MODEL"DEFAULT_RESISTOR_33OHM_2_1"
CDS_LMAN_SYM_OUTLINE"-50,50,100,-50"
CDS_LIB"passive";
"1"
$PN"1"6;
"2"
$PN"2"7;
%"CAPACITOR"
"1","(-2150,6850)","3","passive","I26";
;
$LOCATION"C80"
CDS_LOCATION"C80"
$SEC"1"
CDS_SEC"1"
PACKAGE"0402"
VOLTAGE"10V"
VALUE"0.1UF"
TOLERANCE"10%"
CLS_PN"G105-0B104-CK"
CDS_LIB"passive"
CDS_LMAN_SYM_OUTLINE"0,50,50,-50";
"2"
$PN"2"19;
"1"
$PN"1"18;
%"RESISTOR"
"1","(-6300,6050)","0","passive","I29";
;
$LOCATION"R110"
CDS_LOCATION"R110"
$SEC"1"
CDS_SEC"1"
PACKAGE"0402"
VALUE"33OHM"
TOLERANCE"1%"
CLS_PN"G155-133R0-01"
CDS_LIB"passive"
CDS_LMAN_SYM_OUTLINE"-50,50,100,-50"
SIGNAL_MODEL"DEFAULT_RESISTOR_33OHM_2_1";
"1"
$PN"1"13;
"2"
$PN"2"3;
%"VCC"
"1","(-7100,7400)","0","cls","I32";
;
VOLTAGE"5.0"
HDL_POWER"XP5R0V"
BODY_TYPE"PLUMBING"
CDS_LIB"cls"
CDS_LMAN_SYM_OUTLINE"-250,250,250,-250";
"$PIN0"16;
%"CONN_HDR_2X4_F_S_SMT"
"1","(-4150,6350)","2","connector","I36";
;
LOCATION"P2"
$SEC"1"
CDS_SEC"1"
VALUE"SQW-104-01-F-D-VS-K-TR"
CLS_PN"G200-13079-01"
CDS_LMAN_SYM_OUTLINE"0,0,300,-500"
CDS_LIB"connector";
"8"
$PN"8"2;
"7"
$PN"7"9;
"6"
$PN"6"5;
"5"
$PN"5"3;
"4"
$PN"4"6;
"3"
$PN"3"4;
"2"
$PN"2"18;
"1"
$PN"1"1;
%"RESISTOR"
"2","(-7350,6400)","1","passive","I38";
;
$LOCATION"R268"
CDS_LOCATION"R268"
$SEC"1"
CDS_SEC"1"
PACKAGE"0402"
VALUE"100KOHM"
CLS_PN"G155-11003-01"
CDS_LIB"passive"
CDS_LMAN_SYM_OUTLINE"-50,50,50,-100"
TOLERANCE"1%";
"1"
$PN"1"14;
"2"
$PN"2"3;
%"VCC"
"1","(-7900,6600)","0","cls","I39";
;
VOLTAGE"3.3V"
HDL_POWER"XP3R3V_FPGA"
CDS_LIB"cls"
CDS_LMAN_SYM_OUTLINE"-250,250,250,-250"
BODY_TYPE"PLUMBING";
"$PIN0"14;
%"RESISTOR"
"2","(-7350,6300)","1","passive","I40";
;
$LOCATION"R269"
CDS_LOCATION"R269"
$SEC"1"
CDS_SEC"1"
VALUE"100KOHM"
PACKAGE"0402"
CLS_PN"G155-11003-01"
CDS_LMAN_SYM_OUTLINE"-50,50,50,-100"
CDS_LIB"passive"
TOLERANCE"1%";
"1"
$PN"1"14;
"2"
$PN"2"15;
%"VCC"
"1","(-500,7350)","0","cls","I42";
;
VOLTAGE"3.3V"
HDL_POWER"XP3R3V_FPGA"
CDS_LMAN_SYM_OUTLINE"-250,250,250,-250"
CDS_LIB"cls"
BODY_TYPE"PLUMBING";
"$PIN0"20;
%"CAPACITOR"
"1","(-800,6900)","3","passive","I43";
;
$LOCATION"C81"
CDS_LOCATION"C81"
$SEC"1"
CDS_SEC"1"
VALUE"0.1UF"
VOLTAGE"10V"
PACKAGE"0402"
TOLERANCE"10%"
CLS_PN"G105-0B104-CK"
CDS_LIB"passive"
CDS_LMAN_SYM_OUTLINE"0,50,50,-50";
"2"
$PN"2"19;
"1"
$PN"1"20;
%"CAPACITOR"
"1","(-6850,6950)","3","passive","I44";
;
$LOCATION"C272"
CDS_LOCATION"C272"
$SEC"1"
CDS_SEC"1"
VALUE"0.1UF"
PACKAGE"0402"
VOLTAGE"25V"
CDS_LIB"passive"
CDS_LMAN_SYM_OUTLINE"0,50,50,-50"
TOLERANCE"10%"
CLS_PN"G105-0B104-EK";
"2"
$PN"2"17;
"1"
$PN"1"16;
%"CAPACITOR"
"1","(-2600,6850)","3","passive","I45";
;
$LOCATION"C273"
CDS_LOCATION"C273"
$SEC"1"
CDS_SEC"1"
VALUE"0.1UF"
VOLTAGE"10V"
PACKAGE"0402"
TOLERANCE"10%"
CDS_LIB"passive"
CDS_LMAN_SYM_OUTLINE"0,50,50,-50"
CLS_PN"G105-0B104-CK";
"2"
$PN"2"19;
"1"
$PN"1"18;
%"RESISTOR"
"1","(-6300,5950)","0","passive","I5";
;
$LOCATION"R111"
CDS_LOCATION"R111"
$SEC"1"
CDS_SEC"1"
PACKAGE"0402"
VALUE"33OHM"
TOLERANCE"1%"
CLS_PN"G155-133R0-01"
CDS_LIB"passive"
CDS_LMAN_SYM_OUTLINE"-50,50,100,-50"
SIGNAL_MODEL"DEFAULT_RESISTOR_33OHM_2_1";
"1"
$PN"1"12;
"2"
$PN"2"9;
%"VCC"
"1","(-3850,7400)","0","cls","I54";
;
VOLTAGE"3.3V"
HDL_POWER"XP3R3V_GPS"
BODY_TYPE"PLUMBING"
CDS_LMAN_SYM_OUTLINE"-250,250,250,-250"
CDS_LIB"cls";
"$PIN0"18;
%"FERRITEBEAD"
"1","(-1300,7200)","0","passive","I55";
;
LOCATION"L16"
$SEC"1"
CDS_SEC"1"
VALUE"120OHM"
PACKAGE"0603"
CLS_PN"G191-10100-01"
TOLERANCE"25%"
CDS_LMAN_SYM_OUTLINE"0,0,200,-100"
CDS_LIB"passive";
"2"
$PN"2"20;
"1"
$PN"1"18;
%"FERRITEBEAD"
"1","(-6550,7300)","0","passive","I56";
;
LOCATION"L15"
$SEC"1"
CDS_SEC"1"
PACKAGE"0603"
VALUE"120OHM"
TOLERANCE"25%"
CLS_PN"G191-10100-01"
CDS_LMAN_SYM_OUTLINE"0,0,200,-100"
CDS_LIB"passive";
"2"
$PN"2"1;
"1"
$PN"1"16;
%"RESISTOR"
"1","(-6300,5700)","0","passive","I7";
;
$LOCATION"R113"
CDS_LOCATION"R113"
$SEC"1"
CDS_SEC"1"
VALUE"33OHM"
PACKAGE"0402"
TOLERANCE"1%"
CLS_PN"G155-133R0-01"
SIGNAL_MODEL"DEFAULT_RESISTOR_33OHM_2_1"
CDS_LMAN_SYM_OUTLINE"-50,50,100,-50"
CDS_LIB"passive";
"1"
$PN"1"10;
"2"
$PN"2"3;
%"RESISTOR"
"1","(-6300,5800)","0","passive","I8";
;
$LOCATION"R112"
CDS_LOCATION"R112"
$SEC"1"
CDS_SEC"1"
PACKAGE"0402"
VALUE"33OHM"
TOLERANCE"1%"
CLS_PN"G155-133R0-01"
SIGNAL_MODEL"DEFAULT_RESISTOR_33OHM_2_1"
CDS_LMAN_SYM_OUTLINE"-50,50,100,-50"
CDS_LIB"passive";
"1"
$PN"1"11;
"2"
$PN"2"4;
END.
